# BASEBOARD_FAB2 (Tioga Pass) — schematic netlist excerpt (pin names and nets, part order shuffled) for the footprints in the layout excerpt that follows; sources: Cadence DE-HDL packaged netlist, KiCad conversion of Wiwynn_Tioga_Pass_MB.brd

R9R7  RES  20.0 1% CHIP  pkg 0402  page 167 : A = SMB_SENSOR_TMP421_2_SCL ; B = SMB_SENSOR_STBY_LVC3_SCL
C4A18  CAP_A  0.01UF 25V 10% X7R  pkg 0402V  page 52 : A = M_E_VREF ; B = GND
R3N17  RES  1.00K 1% EMPTY  pkg 0402  page 125 : A = P3V3_STBY ; B = SPI_PCH_IO3

(kicad_pcb
	(version 20260206)
	(generator "pcbnew")
	(generator_version "10.0")
	(general
		(thickness 1.6)
		(legacy_teardrops no)
	)
	(paper "A4")
	(title_block
		(title "Wiwynn_Tioga_Pass_MB.brd")
		(comment 1 "Tioga Pass / footprints 1975-1977 of 4770")
	)
	(layers
		(0 "F.Cu" signal "TOP")
		(4 "In1.Cu" signal "L2GND")
		(6 "In2.Cu" signal "L3")
		(8 "In3.Cu" signal "L4GND")
		(10 "In4.Cu" signal "L5")
		(12 "In5.Cu" signal "L6GND")
		(14 "In6.Cu" signal "L7VCC")
		(16 "In7.Cu" signal "L8VCC")
		(18 "In8.Cu" signal "L9GND")
		(20 "In9.Cu" signal "L10")
		(22 "In10.Cu" signal "L11GND")
		(24 "In11.Cu" signal "L12")
		(26 "In12.Cu" signal "L13GND")
		(2 "B.Cu" signal "BOTTOM")
		(9 "F.Adhes" user "F.Adhesive")
		(11 "B.Adhes" user "B.Adhesive")
		(13 "F.Paste" user "Package Geometry/Pastemask Top")
		(15 "B.Paste" user "Package Geometry/Pastemask Bottom")
		(5 "F.SilkS" user "Ref Des/Silkscreen Top")
		(7 "B.SilkS" user "Ref Des/Silkscreen Bottom")
		(1 "F.Mask" user "Board Geometry/Soldermask Top")
		(3 "B.Mask" user "Board Geometry/Soldermask Bottom")
		(17 "Dwgs.User" user "User.Drawings")
		(19 "Cmts.User" user "User.Comments")
		(21 "Eco1.User" user "User.Eco1")
		(23 "Eco2.User" user "User.Eco2")
		(25 "Edge.Cuts" user "Board Geometry/Outline")
		(27 "Margin" user)
		(31 "F.CrtYd" user "Package Geometry/Place Bound Top")
		(29 "B.CrtYd" user "Package Geometry/Place Bound Bottom")
		(35 "F.Fab" user "Ref Des/Assembly Top")
		(33 "B.Fab" user "Ref Des/Assembly Bottom")
	)
	(footprint ""
		(layer "F.Cu")
		(at 195.4784 -140.0556 90)
		(property "Reference" "C4A18"
			(at 0 0 90)
			(layer "F.SilkS")
			(hide yes)
			(effects
				(font
					(size 1.27 1.27)
				)
			)
		)
		(property "Value" ""
			(at 0 0 90)
			(layer "F.Fab")
			(effects
				(font
					(size 1.27 1.27)
				)
			)
		)
		(duplicate_pad_numbers_are_jumpers no)
		(fp_poly
			(pts
				(xy 0.3048 -0.1016) (xy 0.3048 0.9906) (xy -0.3048 0.9906) (xy -0.3048 -0.1016)
			)
			(stroke
				(width 0)
				(type default)
			)
			(fill no)
			(layer "F.CrtYd")
		)
		(fp_line
			(start 0.3048 -0.1016)
			(end -0.3048 -0.1016)
			(stroke
				(width 0.1)
				(type default)
			)
			(layer "F.Fab")
		)
		(fp_line
			(start -0.3048 -0.1016)
			(end -0.3048 0.9906)
			(stroke
				(width 0.1)
				(type default)
			)
			(layer "F.Fab")
		)
		(fp_line
			(start 0.3048 0.9906)
			(end 0.3048 -0.1016)
			(stroke
				(width 0.1)
				(type default)
			)
			(layer "F.Fab")
		)
		(fp_line
			(start -0.3048 0.9906)
			(end 0.3048 0.9906)
			(stroke
				(width 0.1)
				(type default)
			)
			(layer "F.Fab")
		)
		(pad "1" smd rect
			(at 0 0 90)
			(size 0.508 0.508)
			(layers "F.Cu" "F.Mask" "F.Paste")
			(net "M_E_VREF")
		)
		(pad "2" smd rect
			(at 0 0.889 90)
			(size 0.508 0.508)
			(layers "F.Cu" "F.Mask" "F.Paste")
			(net "GND")
		)
		(zone
			(layer "F.Cu")
			(hatch none 0.5)
			(connect_pads
				(clearance 0)
			)
			(min_thickness 0.25)
			(keepout
				(tracks allowed)
				(vias not_allowed)
				(pads allowed)
				(copperpour not_allowed)
				(footprints allowed)
			)
			(placement
				(enabled no)
				(sheetname "")
			)
			(fill
				(thermal_gap 0.5)
				(thermal_bridge_width 0.5)
				(island_removal_mode 0)
			)
			(polygon
				(pts
					(xy 195.7324 -139.8016) (xy 195.7324 -140.3096) (xy 196.1134 -140.3096) (xy 196.1134 -139.8016)
				)
			)
		)
		(zone
			(layer "F.Cu")
			(hatch none 0.5)
			(connect_pads
				(clearance 0)
			)
			(min_thickness 0.25)
			(keepout
				(tracks not_allowed)
				(vias allowed)
				(pads allowed)
				(copperpour not_allowed)
				(footprints allowed)
			)
			(placement
				(enabled no)
				(sheetname "")
			)
			(fill
				(thermal_gap 0.5)
				(thermal_bridge_width 0.5)
				(island_removal_mode 0)
			)
			(polygon
				(pts
					(xy 196.1134 -139.8016) (xy 196.1134 -140.3096) (xy 195.7324 -140.3096) (xy 195.7324 -139.8016)
				)
			)
		)
	)
	(footprint ""
		(layer "F.Cu")
		(at 1.27 -75.057 180)
		(property "Reference" "R9R7"
			(at 0 0 180)
			(layer "F.SilkS")
			(hide yes)
			(effects
				(font
					(size 1.27 1.27)
				)
			)
		)
		(property "Value" ""
			(at 0 0 180)
			(layer "F.Fab")
			(effects
				(font
					(size 1.27 1.27)
				)
			)
		)
		(duplicate_pad_numbers_are_jumpers no)
		(fp_poly
			(pts
				(xy -0.2794 -0.1016) (xy 0.2794 -0.1016) (xy 0.2794 0.9906) (xy -0.2794 0.9906)
			)
			(stroke
				(width 0)
				(type default)
			)
			(fill no)
			(layer "F.CrtYd")
		)
		(fp_line
			(start 0.2794 0.9906)
			(end 0.2794 -0.1016)
			(stroke
				(width 0.1)
				(type default)
			)
			(layer "F.Fab")
		)
		(fp_line
			(start 0.2794 -0.1016)
			(end -0.2794 -0.1016)
			(stroke
				(width 0.1)
				(type default)
			)
			(layer "F.Fab")
		)
		(fp_line
			(start -0.2794 0.9906)
			(end 0.2794 0.9906)
			(stroke
				(width 0.1)
				(type default)
			)
			(layer "F.Fab")
		)
		(fp_line
			(start -0.2794 -0.1016)
			(end -0.2794 0.9906)
			(stroke
				(width 0.1)
				(type default)
			)
			(layer "F.Fab")
		)
		(pad "1" smd rect
			(at 0 0 180)
			(size 0.508 0.508)
			(layers "F.Cu" "F.Mask" "F.Paste")
			(net "SMB_SENSOR_TMP421_2_SCL")
		)
		(pad "2" smd rect
			(at 0 0.889 180)
			(size 0.508 0.508)
			(layers "F.Cu" "F.Mask" "F.Paste")
			(net "SMB_SENSOR_STBY_LVC3_SCL")
		)
		(zone
			(layer "F.Cu")
			(hatch none 0.5)
			(connect_pads
				(clearance 0)
			)
			(min_thickness 0.25)
			(keepout
				(tracks not_allowed)
				(vias allowed)
				(pads allowed)
				(copperpour not_allowed)
				(footprints allowed)
			)
			(placement
				(enabled no)
				(sheetname "")
			)
			(fill
				(thermal_gap 0.5)
				(thermal_bridge_width 0.5)
				(island_removal_mode 0)
			)
			(polygon
				(pts
					(xy 1.524 -75.692) (xy 1.016 -75.692) (xy 1.016 -75.311) (xy 1.524 -75.311)
				)
			)
		)
		(zone
			(layer "F.Cu")
			(hatch none 0.5)
			(connect_pads
				(clearance 0)
			)
			(min_thickness 0.25)
			(keepout
				(tracks allowed)
				(vias not_allowed)
				(pads allowed)
				(copperpour not_allowed)
				(footprints allowed)
			)
			(placement
				(enabled no)
				(sheetname "")
			)
			(fill
				(thermal_gap 0.5)
				(thermal_bridge_width 0.5)
				(island_removal_mode 0)
			)
			(polygon
				(pts
					(xy 1.524 -75.311) (xy 1.016 -75.311) (xy 1.016 -75.692) (xy 1.524 -75.692)
				)
			)
		)
	)
	(footprint ""
		(layer "F.Cu")
		(at 377.698 -87.3125 180)
		(property "Reference" "R3N17"
			(at -0.8382 -0.67818 180)
			(unlocked yes)
			(layer "F.SilkS")
			(effects
				(font
					(size 0.4064 0.254)
					(thickness 0.1524)
				)
				(justify left)
			)
		)
		(property "Value" ""
			(at 0 0 180)
			(layer "F.Fab")
			(effects
				(font
					(size 1.27 1.27)
				)
			)
		)
		(duplicate_pad_numbers_are_jumpers no)
		(fp_poly
			(pts
				(xy -0.2794 -0.1016) (xy 0.2794 -0.1016) (xy 0.2794 0.9906) (xy -0.2794 0.9906)
			)
			(stroke
				(width 0)
				(type default)
			)
			(fill no)
			(layer "F.CrtYd")
		)
		(fp_line
			(start 0.2794 0.9906)
			(end 0.2794 -0.1016)
			(stroke
				(width 0.1)
				(type default)
			)
			(layer "F.Fab")
		)
		(fp_line
			(start 0.2794 -0.1016)
			(end -0.2794 -0.1016)
			(stroke
				(width 0.1)
				(type default)
			)
			(layer "F.Fab")
		)
		(fp_line
			(start -0.2794 0.9906)
			(end 0.2794 0.9906)
			(stroke
				(width 0.1)
				(type default)
			)
			(layer "F.Fab")
		)
		(fp_line
			(start -0.2794 -0.1016)
			(end -0.2794 0.9906)
			(stroke
				(width 0.1)
				(type default)
			)
			(layer "F.Fab")
		)
		(pad "1" smd rect
			(at 0 0 180)
			(size 0.508 0.508)
			(layers "F.Cu" "F.Mask" "F.Paste")
			(net "P3V3_STBY")
		)
		(pad "2" smd rect
			(at 0 0.889 180)
			(size 0.508 0.508)
			(layers "F.Cu" "F.Mask" "F.Paste")
			(net "SPI_PCH_IO3")
		)
		(zone
			(layer "F.Cu")
			(hatch none 0.5)
			(connect_pads
				(clearance 0)
			)
			(min_thickness 0.25)
			(keepout
				(tracks not_allowed)
				(vias allowed)
				(pads allowed)
				(copperpour not_allowed)
				(footprints allowed)
			)
			(placement
				(enabled no)
				(sheetname "")
			)
			(fill
				(thermal_gap 0.5)
				(thermal_bridge_width 0.5)
				(island_removal_mode 0)
			)
			(polygon
				(pts
					(xy 377.952 -87.9475) (xy 377.444 -87.9475) (xy 377.444 -87.5665) (xy 377.952 -87.5665)
				)
			)
		)
		(zone
			(layer "F.Cu")
			(hatch none 0.5)
			(connect_pads
				(clearance 0)
			)
			(min_thickness 0.25)
			(keepout
				(tracks allowed)
				(vias not_allowed)
				(pads allowed)
				(copperpour not_allowed)
				(footprints allowed)
			)
			(placement
				(enabled no)
				(sheetname "")
			)
			(fill
				(thermal_gap 0.5)
				(thermal_bridge_width 0.5)
				(island_removal_mode 0)
			)
			(polygon
				(pts
					(xy 377.952 -87.5665) (xy 377.444 -87.5665) (xy 377.444 -87.9475) (xy 377.952 -87.9475)
				)
			)
		)
	)
)
